(kicad_pcb
	(version 20241229)
	(generator "pcbnew")
	(generator_version "9.0")
	(general
		(thickness 1.711)
		(legacy_teardrops no)
	)
	(paper "A4")
	(title_block
		(title "Antmicro Baseboard for Jetson AGX Thor")
		(date "2026-02-18")
		(rev "1.1.0")
		(company "Antmicro Ltd")
		(comment 1 "www.antmicro.com")
		(comment 9 "footprints 716-719 of 1170")
	)
	(layers
		(0 "F.Cu" signal)
		(4 "In1.Cu" signal)
		(6 "In2.Cu" signal)
		(8 "In3.Cu" signal)
		(10 "In4.Cu" jumper)
		(12 "In5.Cu" signal)
		(14 "In6.Cu" signal)
		(16 "In7.Cu" signal)
		(18 "In8.Cu" signal)
		(2 "B.Cu" signal)
		(9 "F.Adhes" user "F.Adhesive")
		(11 "B.Adhes" user "B.Adhesive")
		(13 "F.Paste" user)
		(15 "B.Paste" user)
		(5 "F.SilkS" user "F.Silkscreen")
		(7 "B.SilkS" user "B.Silkscreen")
		(1 "F.Mask" user)
		(3 "B.Mask" user)
		(17 "Dwgs.User" user "User.Drawings")
		(19 "Cmts.User" user "User.Comments")
		(21 "Eco1.User" user "User.Eco1")
		(23 "Eco2.User" user "User.Eco2")
		(25 "Edge.Cuts" user)
		(27 "Margin" user)
		(31 "F.CrtYd" user "F.Courtyard")
		(29 "B.CrtYd" user "B.Courtyard")
		(35 "F.Fab" user)
		(33 "B.Fab" user)
	)
	(footprint "antmicro-footprints:MS621FE-FL11E"
		(layer "B.Cu")
		(at 142.480532 148.21 90)
		(property "Reference" "BT1"
			(at -1.66 2.249468 0)
			(layer "B.SilkS")
			(effects
				(font
					(size 0.7 0.7)
					(thickness 0.15)
				)
				(justify right top mirror)
			)
		)
		(property "Value" "Battery_Holder_MS621FE-FL11E"
			(at -0.001 -6.2 90)
			(layer "B.Fab")
			(effects
				(font
					(size 0.7 0.7)
					(thickness 0.15)
				)
				(justify right top mirror)
			)
		)
		(property "Datasheet" "https://www.sii.co.jp/en/me/datasheets/ms-rechargeable/ms621fe/"
			(at 0 0 90)
			(layer "B.Fab")
			(hide yes)
			(effects
				(font
					(size 1.27 1.27)
					(thickness 0.15)
				)
				(justify mirror)
			)
		)
		(property "Description" "Rechargeable Battery, Coin Cell, Single Cell, 3 V, Lithium Manganese Dioxide, 5.5 mAh, Button Cell"
			(at 0 0 90)
			(layer "B.Fab")
			(hide yes)
			(effects
				(font
					(size 1.27 1.27)
					(thickness 0.15)
				)
				(justify mirror)
			)
		)
		(property "Manufacturer" "Seiko Instruments"
			(at 0 0 270)
			(unlocked yes)
			(layer "B.Fab")
			(hide yes)
			(effects
				(font
					(size 1 1)
					(thickness 0.15)
				)
				(justify mirror)
			)
		)
		(property "MPN" "MS621FE-FL11E"
			(at 0 0 270)
			(unlocked yes)
			(layer "B.Fab")
			(hide yes)
			(effects
				(font
					(size 1 1)
					(thickness 0.15)
				)
				(justify mirror)
			)
		)
		(property "Author" "Antmicro"
			(at 0 0 270)
			(unlocked yes)
			(layer "B.Fab")
			(hide yes)
			(effects
				(font
					(size 1 1)
					(thickness 0.15)
				)
				(justify mirror)
			)
		)
		(property "License" "Apache-2.0"
			(at 0 0 270)
			(unlocked yes)
			(layer "B.Fab")
			(hide yes)
			(effects
				(font
					(size 1 1)
					(thickness 0.15)
				)
				(justify mirror)
			)
		)
		(sheetname "/SoM_Power/")
		(sheetfile "som_power.kicad_sch")
		(attr smd)
		(fp_arc
			(start -1.2 2.15)
			(mid 0 -4.834)
			(end 1.2 2.15)
			(stroke
				(width 0.15)
				(type solid)
			)
			(layer "B.SilkS")
		)
		(fp_line
			(start 1.275 5.2)
			(end 1.275 2.425)
			(stroke
				(width 0.05)
				(type solid)
			)
			(layer "B.CrtYd")
		)
		(fp_line
			(start 1.275 5.2)
			(end -1.275 5.2)
			(stroke
				(width 0.05)
				(type solid)
			)
			(layer "B.CrtYd")
		)
		(fp_line
			(start -1.275 5.2)
			(end -1.275 2.425)
			(stroke
				(width 0.05)
				(type solid)
			)
			(layer "B.CrtYd")
		)
		(fp_arc
			(start -1.275 2.425)
			(mid 0 -5.143374)
			(end 1.275 2.425)
			(stroke
				(width 0.05)
				(type solid)
			)
			(layer "B.CrtYd")
		)
		(fp_line
			(start -1.2 4.65)
			(end -1.2 2.04)
			(stroke
				(width 0.15)
				(type solid)
			)
			(layer "B.Fab")
		)
		(fp_line
			(start 1.2 5.05)
			(end 1.2 2.04)
			(stroke
				(width 0.15)
				(type solid)
			)
			(layer "B.Fab")
		)
		(fp_line
			(start 1.2 5.05)
			(end -0.8 5.05)
			(stroke
				(width 0.15)
				(type solid)
			)
			(layer "B.Fab")
		)
		(fp_line
			(start -0.8 5.05)
			(end -1.2 4.65)
			(stroke
				(width 0.15)
				(type solid)
			)
			(layer "B.Fab")
		)
		(fp_circle
			(center -0.001 -1.25)
			(end -0.001 2.25)
			(stroke
				(width 0.15)
				(type solid)
			)
			(fill no)
			(layer "B.Fab")
		)
		(fp_text user "${REFERENCE}"
			(at -3.501 -11.8 90)
			(layer "B.Fab")
			(effects
				(font
					(size 0.7 0.7)
					(thickness 0.15)
				)
				(justify right top mirror)
			)
		)
		(fp_text user "COPPER KEEPOUT"
			(at -0.2 3.14 0)
			(unlocked yes)
			(layer "B.Fab")
			(effects
				(font
					(size 0.4 0.4)
					(thickness 0.1)
				)
				(justify left bottom mirror)
			)
		)
		(fp_text user "Author: Antmicro"
			(at -3.501 -9.4 90)
			(layer "B.Fab")
			(effects
				(font
					(size 0.7 0.7)
					(thickness 0.15)
				)
				(justify right top mirror)
			)
		)
		(fp_text user "License: Apache-2.0"
			(at -3.501 -8.2 90)
			(layer "B.Fab")
			(effects
				(font
					(size 0.7 0.7)
					(thickness 0.15)
				)
				(justify right top mirror)
			)
		)
		(pad "1" smd rect
			(at -0.75 4.05 180)
			(size 1.8 0.75)
			(layers "B.Cu" "B.Mask" "B.Paste")
			(net 10 "Net-(BT1-+)")
			(pinfunction "+")
			(pintype "passive")
		)
		(pad "2" smd rect
			(at 0.75 4.05 180)
			(size 1.8 0.75)
			(layers "B.Cu" "B.Mask" "B.Paste")
			(net 1 "GND")
			(pinfunction "-")
			(pintype "passive")
		)
		(zone
			(net 0)
			(net_name "")
			(layers "B.Cu" "B.CrtYd")
			(hatch edge 0.508)
			(connect_pads
				(clearance 0)
			)
			(min_thickness 0.254)
			(filled_areas_thickness no)
			(keepout
				(tracks allowed)
				(vias not_allowed)
				(pads not_allowed)
				(copperpour not_allowed)
				(footprints allowed)
			)
			(placement
				(enabled no)
				(sheetname "")
			)
			(fill
				(thermal_gap 0.508)
				(thermal_bridge_width 0.508)
			)
			(polygon
				(pts
					(xy 139.980532 149.37) (xy 145.620532 149.37) (xy 145.620532 147.05) (xy 139.980532 147.05)
				)
			)
		)
	)
	(footprint "antmicro-footprints:R_0402_1005Metric"
		(layer "B.Cu")
		(at 220.4 123.391698)
		(descr "Resistor SMD 0402")
		(tags "resistor SMD 0402")
		(property "Reference" "R335"
			(at -0.9 1.708302 0)
			(layer "B.SilkS")
			(effects
				(font
					(size 0.7 0.7)
					(thickness 0.15)
				)
				(justify right top mirror)
			)
		)
		(property "Value" "R_10k_0402"
			(at -1.011843 -1.772047 0)
			(layer "B.Fab")
			(effects
				(font
					(size 0.7 0.7)
					(thickness 0.15)
				)
				(justify right top mirror)
			)
		)
		(property "Datasheet" "https://www.bourns.com/docs/product-datasheets/cr.pdf"
			(at 0 0 0)
			(layer "B.Fab")
			(hide yes)
			(effects
				(font
					(size 1.27 1.27)
					(thickness 0.15)
				)
				(justify mirror)
			)
		)
		(property "Description" "SMD Chip Resistor, 10 kohm, ± 1%, 62.5 mW, 0402 [1005 Metric], Thick Film, General Purpose"
			(at 0 0 0)
			(layer "B.Fab")
			(hide yes)
			(effects
				(font
					(size 1.27 1.27)
					(thickness 0.15)
				)
				(justify mirror)
			)
		)
		(property "MPN" "CR0402-FX-1002GLF"
			(at 0 0 180)
			(unlocked yes)
			(layer "B.Fab")
			(hide yes)
			(effects
				(font
					(size 1 1)
					(thickness 0.15)
				)
				(justify mirror)
			)
		)
		(property "Manufacturer" "Bourns"
			(at 0 0 180)
			(unlocked yes)
			(layer "B.Fab")
			(hide yes)
			(effects
				(font
					(size 1 1)
					(thickness 0.15)
				)
				(justify mirror)
			)
		)
		(property "License" "Apache-2.0"
			(at 0 0 180)
			(unlocked yes)
			(layer "B.Fab")
			(hide yes)
			(effects
				(font
					(size 1 1)
					(thickness 0.15)
				)
				(justify mirror)
			)
		)
		(property "Author" "Antmicro"
			(at 0 0 180)
			(unlocked yes)
			(layer "B.Fab")
			(hide yes)
			(effects
				(font
					(size 1 1)
					(thickness 0.15)
				)
				(justify mirror)
			)
		)
		(property "Val" "10k"
			(at 0 0 180)
			(unlocked yes)
			(layer "B.Fab")
			(hide yes)
			(effects
				(font
					(size 1 1)
					(thickness 0.15)
				)
				(justify mirror)
			)
		)
		(property "Tolerance" "1%"
			(at 0 0 180)
			(unlocked yes)
			(layer "B.Fab")
			(hide yes)
			(effects
				(font
					(size 1 1)
					(thickness 0.15)
				)
				(justify mirror)
			)
		)
		(sheetname "/USB Hub/")
		(sheetfile "usb_hub.kicad_sch")
		(attr smd)
		(fp_rect
			(start -0.925 0.47)
			(end 0.925 -0.47)
			(stroke
				(width 0.05)
				(type default)
			)
			(fill no)
			(layer "B.CrtYd")
		)
		(fp_rect
			(start -0.5 0.25)
			(end 0.5 -0.25)
			(stroke
				(width 0.15)
				(type solid)
			)
			(fill no)
			(layer "B.Fab")
		)
		(fp_text user "${REFERENCE}"
			(at -0.95 -3.168 0)
			(layer "B.Fab")
			(effects
				(font
					(size 0.7 0.7)
					(thickness 0.15)
				)
				(justify right top mirror)
			)
		)
		(fp_text user "License: Apache-2.0"
			(at -0.95 -5.169 0)
			(layer "B.Fab")
			(effects
				(font
					(size 0.7 0.7)
					(thickness 0.15)
				)
				(justify right top mirror)
			)
		)
		(fp_text user "Author: Antmicro"
			(at -0.95 -4.169 0)
			(layer "B.Fab")
			(effects
				(font
					(size 0.7 0.7)
					(thickness 0.15)
				)
				(justify right top mirror)
			)
		)
		(pad "1" smd roundrect
			(at -0.48 0)
			(size 0.59 0.64)
			(layers "B.Cu" "B.Mask" "B.Paste")
			(roundrect_rratio 0.25)
			(net 1095 "/USB Hub/DP1_VCONN2")
			(pintype "passive")
		)
		(pad "2" smd roundrect
			(at 0.48 0)
			(size 0.59 0.64)
			(layers "B.Cu" "B.Mask" "B.Paste")
			(roundrect_rratio 0.25)
			(net 1 "GND")
			(pintype "passive")
		)
	)
	(footprint "antmicro-footprints:SOT-523"
		(layer "B.Cu")
		(at 169 60.8 -90)
		(property "Reference" "Q16"
			(at -1.2 -1 180)
			(layer "B.SilkS")
			(effects
				(font
					(size 0.7 0.7)
					(thickness 0.15)
				)
				(justify left bottom mirror)
			)
		)
		(property "Value" "DMG1012T-7"
			(at 0.1 -1.824 90)
			(layer "B.Fab")
			(effects
				(font
					(size 0.7 0.7)
					(thickness 0.15)
				)
				(justify left bottom mirror)
			)
		)
		(property "Datasheet" "https://www.diodes.com/assets/Datasheets/ds31783.pdf"
			(at 0 0 90)
			(layer "B.Fab")
			(hide yes)
			(effects
				(font
					(size 1.27 1.27)
					(thickness 0.15)
				)
				(justify mirror)
			)
		)
		(property "Description" "Power MOSFET, N Channel, 20 V, 630 mA, 0.3 ohm, SOT-523, Surface Mount"
			(at 0 0 90)
			(layer "B.Fab")
			(hide yes)
			(effects
				(font
					(size 1.27 1.27)
					(thickness 0.15)
				)
				(justify mirror)
			)
		)
		(property "MPN" "DMG1012T-7"
			(at 0 0 90)
			(unlocked yes)
			(layer "B.Fab")
			(hide yes)
			(effects
				(font
					(size 1 1)
					(thickness 0.15)
				)
				(justify mirror)
			)
		)
		(property "Manufacturer" "Diodes Incorporated"
			(at 0 0 90)
			(unlocked yes)
			(layer "B.Fab")
			(hide yes)
			(effects
				(font
					(size 1 1)
					(thickness 0.15)
				)
				(justify mirror)
			)
		)
		(property "Author" "Antmicro"
			(at 0 0 90)
			(unlocked yes)
			(layer "B.Fab")
			(hide yes)
			(effects
				(font
					(size 1 1)
					(thickness 0.15)
				)
				(justify mirror)
			)
		)
		(property "License" "Apache-2.0"
			(at 0 0 90)
			(unlocked yes)
			(layer "B.Fab")
			(hide yes)
			(effects
				(font
					(size 1 1)
					(thickness 0.15)
				)
				(justify mirror)
			)
		)
		(sheetname "/Power/")
		(sheetfile "power.kicad_sch")
		(attr smd)
		(fp_line
			(start -0.725 0.551)
			(end -0.277 0.551)
			(stroke
				(width 0.15)
				(type solid)
			)
			(layer "B.SilkS")
		)
		(fp_line
			(start -0.277 0.551)
			(end -0.277 0.75)
			(stroke
				(width 0.15)
				(type solid)
			)
			(layer "B.SilkS")
		)
		(fp_line
			(start -0.927 0.351)
			(end -0.725 0.551)
			(stroke
				(width 0.15)
				(type solid)
			)
			(layer "B.SilkS")
		)
		(fp_line
			(start -0.927 0.051)
			(end -0.927 0.351)
			(stroke
				(width 0.15)
				(type solid)
			)
			(layer "B.SilkS")
		)
		(fp_circle
			(center -0.9652 -0.9652)
			(end -0.9152 -0.9652)
			(stroke
				(width 0.15)
				(type solid)
			)
			(fill yes)
			(layer "B.SilkS")
		)
		(fp_line
			(start -1.12 1.16)
			(end 1.1 1.16)
			(stroke
				(width 0.05)
				(type solid)
			)
			(layer "B.CrtYd")
		)
		(fp_line
			(start -1.12 1.16)
			(end -1.12 -1.15)
			(stroke
				(width 0.05)
				(type solid)
			)
			(layer "B.CrtYd")
		)
		(fp_line
			(start 1.1 1.16)
			(end 1.1 -1.15)
			(stroke
				(width 0.05)
				(type solid)
			)
			(layer "B.CrtYd")
		)
		(fp_line
			(start -1.12 -1.15)
			(end 1.1 -1.15)
			(stroke
				(width 0.05)
				(type solid)
			)
			(layer "B.CrtYd")
		)
		(fp_line
			(start -0.652 0.425)
			(end -0.802 0.276)
			(stroke
				(width 0.15)
				(type solid)
			)
			(layer "B.Fab")
		)
		(fp_line
			(start 0.8 0.425)
			(end -0.652 0.425)
			(stroke
				(width 0.15)
				(type solid)
			)
			(layer "B.Fab")
		)
		(fp_line
			(start 0.8 0.425)
			(end 0.8 -0.424)
			(stroke
				(width 0.15)
				(type solid)
			)
			(layer "B.Fab")
		)
		(fp_line
			(start -0.802 0.276)
			(end -0.802 -0.424)
			(stroke
				(width 0.15)
				(type solid)
			)
			(layer "B.Fab")
		)
		(fp_line
			(start 0.8 -0.424)
			(end -0.802 -0.424)
			(stroke
				(width 0.15)
				(type solid)
			)
			(layer "B.Fab")
		)
		(fp_circle
			(center -0.9652 -0.9652)
			(end -0.9144 -0.9652)
			(stroke
				(width 0.15)
				(type solid)
			)
			(fill no)
			(layer "B.Fab")
		)
		(fp_text user "${REFERENCE}"
			(at -1.12 -3.824 90)
			(layer "B.Fab")
			(effects
				(font
					(size 0.7 0.7)
					(thickness 0.15)
				)
				(justify left bottom mirror)
			)
		)
		(fp_text user "Author: Antmicro"
			(at -1.12 -6.224 90)
			(layer "B.Fab")
			(effects
				(font
					(size 0.7 0.7)
					(thickness 0.15)
				)
				(justify left bottom mirror)
			)
		)
		(fp_text user "License: Apache-2.0"
			(at -1.12 -5.024 90)
			(layer "B.Fab")
			(effects
				(font
					(size 0.7 0.7)
					(thickness 0.15)
				)
				(justify left bottom mirror)
			)
		)
		(pad "1" smd rect
			(at -0.5 -0.65 270)
			(size 0.4 0.51)
			(layers "B.Cu" "B.Mask" "B.Paste")
			(net 11 "+1V8")
			(pinfunction "G")
			(pintype "input")
		)
		(pad "2" smd rect
			(at 0.498 -0.65 270)
			(size 0.4 0.51)
			(layers "B.Cu" "B.Mask" "B.Paste")
			(net 1 "GND")
			(pinfunction "S")
			(pintype "passive")
		)
		(pad "3" smd rect
			(at 0 0.652 270)
			(size 0.4 0.51)
			(layers "B.Cu" "B.Mask" "B.Paste")
			(net 644 "Net-(D43-C)")
			(pinfunction "D")
			(pintype "passive")
		)
	)
	(footprint "antmicro-footprints:C_0603_1608Metric_EIA"
		(layer "B.Cu")
		(at 124.6 139 180)
		(descr "Capacitor SMD 0603, IPC-7351 Density Level A")
		(tags "Capacitor 0603")
		(property "Reference" "C198"
			(at -4.6 -0.4 0)
			(layer "B.SilkS")
			(effects
				(font
					(size 0.7 0.7)
					(thickness 0.15)
				)
				(justify left bottom mirror)
			)
		)
		(property "Value" "C_22u_16V_0603"
			(at -1.42757 -1.770288 0)
			(layer "B.Fab")
			(effects
				(font
					(size 0.7 0.7)
					(thickness 0.15)
				)
				(justify left bottom mirror)
			)
		)
		(property "Datasheet" "https://product.samsungsem.com/mlcc/CL10A226MO7JZN.do"
			(at 0 0 0)
			(layer "B.Fab")
			(hide yes)
			(effects
				(font
					(size 1.27 1.27)
					(thickness 0.15)
				)
				(justify mirror)
			)
		)
		(property "Description" "SMD Multilayer Ceramic Capacitor"
			(at 0 0 0)
			(layer "B.Fab")
			(hide yes)
			(effects
				(font
					(size 1.27 1.27)
					(thickness 0.15)
				)
				(justify mirror)
			)
		)
		(property "MPN" "CL10A226MO7JZNC"
			(at 0 0 180)
			(unlocked yes)
			(layer "B.Fab")
			(hide yes)
			(effects
				(font
					(size 1 1)
					(thickness 0.15)
				)
				(justify mirror)
			)
		)
		(property "Manufacturer" "Samsung Electro-Mechanics"
			(at 0 0 180)
			(unlocked yes)
			(layer "B.Fab")
			(hide yes)
			(effects
				(font
					(size 1 1)
					(thickness 0.15)
				)
				(justify mirror)
			)
		)
		(property "License" "Apache-2.0"
			(at 0 0 180)
			(unlocked yes)
			(layer "B.Fab")
			(hide yes)
			(effects
				(font
					(size 1 1)
					(thickness 0.15)
				)
				(justify mirror)
			)
		)
		(property "Author" "Antmicro"
			(at 0 0 180)
			(unlocked yes)
			(layer "B.Fab")
			(hide yes)
			(effects
				(font
					(size 1 1)
					(thickness 0.15)
				)
				(justify mirror)
			)
		)
		(property "Val" "22u"
			(at 0 0 180)
			(unlocked yes)
			(layer "B.Fab")
			(hide yes)
			(effects
				(font
					(size 1 1)
					(thickness 0.15)
				)
				(justify mirror)
			)
		)
		(property "Voltage" "16V"
			(at 0 0 180)
			(unlocked yes)
			(layer "B.Fab")
			(hide yes)
			(effects
				(font
					(size 1 1)
					(thickness 0.15)
				)
				(justify mirror)
			)
		)
		(property "Dielectric" ""
			(at 0 0 180)
			(unlocked yes)
			(layer "B.Fab")
			(hide yes)
			(effects
				(font
					(size 1 1)
					(thickness 0.15)
				)
				(justify mirror)
			)
		)
		(sheetname "/M.2/")
		(sheetfile "m2.kicad_sch")
		(attr smd)
		(fp_line
			(start -0.15 0.55)
			(end 0.15 0.55)
			(stroke
				(width 0.15)
				(type solid)
			)
			(layer "B.SilkS")
		)
		(fp_line
			(start -0.15 -0.55)
			(end 0.15 -0.55)
			(stroke
				(width 0.15)
				(type solid)
			)
			(layer "B.SilkS")
		)
		(fp_rect
			(start -1.25 0.65)
			(end 1.25 -0.65)
			(stroke
				(width 0.05)
				(type solid)
			)
			(fill no)
			(layer "B.CrtYd")
		)
		(fp_rect
			(start -0.8 0.45)
			(end 0.8 -0.45)
			(stroke
				(width 0.15)
				(type solid)
			)
			(fill no)
			(layer "B.Fab")
		)
		(fp_text user "${REFERENCE}"
			(at -1.682 -3.895 0)
			(layer "B.Fab")
			(effects
				(font
					(size 0.7 0.7)
					(thickness 0.15)
				)
				(justify left bottom mirror)
			)
		)
		(fp_text user "License: Apache-2.0"
			(at -1.682 -5.895 0)
			(layer "B.Fab")
			(effects
				(font
					(size 0.7 0.7)
					(thickness 0.15)
				)
				(justify left bottom mirror)
			)
		)
		(fp_text user "Author: Antmicro"
			(at -1.682 -4.894 0)
			(layer "B.Fab")
			(effects
				(font
					(size 0.7 0.7)
					(thickness 0.15)
				)
				(justify left bottom mirror)
			)
		)
		(pad "1" smd roundrect
			(at -0.7 0 180)
			(size 0.8 1.1)
			(layers "B.Cu" "B.Mask" "B.Paste")
			(roundrect_rratio 0.2)
			(net 1 "GND")
			(pintype "passive")
		)
		(pad "2" smd roundrect
			(at 0.7 0 180)
			(size 0.8 1.1)
			(layers "B.Cu" "B.Mask" "B.Paste")
			(roundrect_rratio 0.2)
			(net 2 "+3V3")
			(pintype "passive")
		)
	)
)
